(kicad_pcb
	(version 20260206)
	(generator "pcbnew")
	(generator_version "10.0")
	(general
		(thickness 1.6)
		(legacy_teardrops no)
	)
	(paper "A4")
	(title_block
		(title "Wiwynn_Tioga_Pass_MB.brd")
		(comment 1 "Tioga Pass / footprints 369-375 of 4770")
	)
	(layers
		(0 "F.Cu" signal "TOP")
		(4 "In1.Cu" signal "L2GND")
		(6 "In2.Cu" signal "L3")
		(8 "In3.Cu" signal "L4GND")
		(10 "In4.Cu" signal "L5")
		(12 "In5.Cu" signal "L6GND")
		(14 "In6.Cu" signal "L7VCC")
		(16 "In7.Cu" signal "L8VCC")
		(18 "In8.Cu" signal "L9GND")
		(20 "In9.Cu" signal "L10")
		(22 "In10.Cu" signal "L11GND")
		(24 "In11.Cu" signal "L12")
		(26 "In12.Cu" signal "L13GND")
		(2 "B.Cu" signal "BOTTOM")
		(9 "F.Adhes" user "F.Adhesive")
		(11 "B.Adhes" user "B.Adhesive")
		(13 "F.Paste" user "Package Geometry/Pastemask Top")
		(15 "B.Paste" user "Package Geometry/Pastemask Bottom")
		(5 "F.SilkS" user "Ref Des/Silkscreen Top")
		(7 "B.SilkS" user "Ref Des/Silkscreen Bottom")
		(1 "F.Mask" user "Board Geometry/Soldermask Top")
		(3 "B.Mask" user "Board Geometry/Soldermask Bottom")
		(17 "Dwgs.User" user "User.Drawings")
		(19 "Cmts.User" user "User.Comments")
		(21 "Eco1.User" user "User.Eco1")
		(23 "Eco2.User" user "User.Eco2")
		(25 "Edge.Cuts" user "Board Geometry/Outline")
		(27 "Margin" user)
		(31 "F.CrtYd" user "Package Geometry/Place Bound Top")
		(29 "B.CrtYd" user "Package Geometry/Place Bound Bottom")
		(35 "F.Fab" user "Ref Des/Assembly Top")
		(33 "B.Fab" user "Ref Des/Assembly Bottom")
	)
	(footprint ""
		(layer "F.Cu")
		(at 411.0355 -108.204 -90)
		(property "Reference" "R2N5"
			(at 0 0 270)
			(layer "F.SilkS")
			(hide yes)
			(effects
				(font
					(size 1.27 1.27)
				)
			)
		)
		(property "Value" ""
			(at 0 0 270)
			(layer "F.Fab")
			(effects
				(font
					(size 1.27 1.27)
				)
			)
		)
		(duplicate_pad_numbers_are_jumpers no)
		(fp_poly
			(pts
				(xy -0.2794 -0.1016) (xy 0.2794 -0.1016) (xy 0.2794 0.9906) (xy -0.2794 0.9906)
			)
			(stroke
				(width 0)
				(type default)
			)
			(fill no)
			(layer "F.CrtYd")
		)
		(fp_line
			(start -0.2794 0.9906)
			(end 0.2794 0.9906)
			(stroke
				(width 0.1)
				(type default)
			)
			(layer "F.Fab")
		)
		(fp_line
			(start 0.2794 0.9906)
			(end 0.2794 -0.1016)
			(stroke
				(width 0.1)
				(type default)
			)
			(layer "F.Fab")
		)
		(fp_line
			(start -0.2794 -0.1016)
			(end -0.2794 0.9906)
			(stroke
				(width 0.1)
				(type default)
			)
			(layer "F.Fab")
		)
		(fp_line
			(start 0.2794 -0.1016)
			(end -0.2794 -0.1016)
			(stroke
				(width 0.1)
				(type default)
			)
			(layer "F.Fab")
		)
		(pad "1" smd rect
			(at 0 0 270)
			(size 0.508 0.508)
			(layers "F.Cu" "F.Mask" "F.Paste")
			(net "P3V3_STBY")
		)
		(pad "2" smd rect
			(at 0 0.889 270)
			(size 0.508 0.508)
			(layers "F.Cu" "F.Mask" "F.Paste")
			(net "SMB_SMLINK0_STBY_LVC3_SCL")
		)
		(zone
			(layer "F.Cu")
			(hatch none 0.5)
			(connect_pads
				(clearance 0)
			)
			(min_thickness 0.25)
			(keepout
				(tracks not_allowed)
				(vias allowed)
				(pads allowed)
				(copperpour not_allowed)
				(footprints allowed)
			)
			(placement
				(enabled no)
				(sheetname "")
			)
			(fill
				(thermal_gap 0.5)
				(thermal_bridge_width 0.5)
				(island_removal_mode 0)
			)
			(polygon
				(pts
					(xy 410.4005 -108.458) (xy 410.4005 -107.95) (xy 410.7815 -107.95) (xy 410.7815 -108.458)
				)
			)
		)
		(zone
			(layer "F.Cu")
			(hatch none 0.5)
			(connect_pads
				(clearance 0)
			)
			(min_thickness 0.25)
			(keepout
				(tracks allowed)
				(vias not_allowed)
				(pads allowed)
				(copperpour not_allowed)
				(footprints allowed)
			)
			(placement
				(enabled no)
				(sheetname "")
			)
			(fill
				(thermal_gap 0.5)
				(thermal_bridge_width 0.5)
				(island_removal_mode 0)
			)
			(polygon
				(pts
					(xy 410.7815 -108.458) (xy 410.7815 -107.95) (xy 410.4005 -107.95) (xy 410.4005 -108.458)
				)
			)
		)
	)
	(footprint ""
		(layer "F.Cu")
		(at 361.188 -133.985)
		(property "Reference" "C7B3"
			(at 0 0 0)
			(layer "F.SilkS")
			(hide yes)
			(effects
				(font
					(size 1.27 1.27)
				)
			)
		)
		(property "Value" ""
			(at 0 0 0)
			(layer "F.Fab")
			(effects
				(font
					(size 1.27 1.27)
				)
			)
		)
		(duplicate_pad_numbers_are_jumpers no)
		(fp_poly
			(pts
				(xy 0.3048 -0.1016) (xy 0.3048 0.9906) (xy -0.3048 0.9906) (xy -0.3048 -0.1016)
			)
			(stroke
				(width 0)
				(type default)
			)
			(fill no)
			(layer "F.CrtYd")
		)
		(fp_line
			(start -0.3048 -0.1016)
			(end -0.3048 0.9906)
			(stroke
				(width 0.1)
				(type default)
			)
			(layer "F.Fab")
		)
		(fp_line
			(start -0.3048 0.9906)
			(end 0.3048 0.9906)
			(stroke
				(width 0.1)
				(type default)
			)
			(layer "F.Fab")
		)
		(fp_line
			(start 0.3048 -0.1016)
			(end -0.3048 -0.1016)
			(stroke
				(width 0.1)
				(type default)
			)
			(layer "F.Fab")
		)
		(fp_line
			(start 0.3048 0.9906)
			(end 0.3048 -0.1016)
			(stroke
				(width 0.1)
				(type default)
			)
			(layer "F.Fab")
		)
		(pad "1" smd rect
			(at 0 0)
			(size 0.508 0.508)
			(layers "F.Cu" "F.Mask" "F.Paste")
			(net "PWRGD_PVDDQ_DEF_R")
		)
		(pad "2" smd rect
			(at 0 0.889)
			(size 0.508 0.508)
			(layers "F.Cu" "F.Mask" "F.Paste")
			(net "GND")
		)
		(zone
			(layer "F.Cu")
			(hatch none 0.5)
			(connect_pads
				(clearance 0)
			)
			(min_thickness 0.25)
			(keepout
				(tracks allowed)
				(vias not_allowed)
				(pads allowed)
				(copperpour not_allowed)
				(footprints allowed)
			)
			(placement
				(enabled no)
				(sheetname "")
			)
			(fill
				(thermal_gap 0.5)
				(thermal_bridge_width 0.5)
				(island_removal_mode 0)
			)
			(polygon
				(pts
					(xy 360.934 -133.731) (xy 361.442 -133.731) (xy 361.442 -133.35) (xy 360.934 -133.35)
				)
			)
		)
		(zone
			(layer "F.Cu")
			(hatch none 0.5)
			(connect_pads
				(clearance 0)
			)
			(min_thickness 0.25)
			(keepout
				(tracks not_allowed)
				(vias allowed)
				(pads allowed)
				(copperpour not_allowed)
				(footprints allowed)
			)
			(placement
				(enabled no)
				(sheetname "")
			)
			(fill
				(thermal_gap 0.5)
				(thermal_bridge_width 0.5)
				(island_removal_mode 0)
			)
			(polygon
				(pts
					(xy 360.934 -133.35) (xy 361.442 -133.35) (xy 361.442 -133.731) (xy 360.934 -133.731)
				)
			)
		)
	)
	(footprint ""
		(layer "F.Cu")
		(at 457.2 -31.735014 180)
		(property "Reference" "U9F3"
			(at -0.508 2.56667 180)
			(unlocked yes)
			(layer "F.SilkS")
			(effects
				(font
					(size 0.7874 0.5842)
					(thickness 0.1524)
				)
				(justify left)
			)
		)
		(property "Value" ""
			(at 0 0 180)
			(layer "F.Fab")
			(effects
				(font
					(size 1.27 1.27)
				)
			)
		)
		(duplicate_pad_numbers_are_jumpers no)
		(fp_circle
			(center -0.90805 -0.431546)
			(end -1.03505 -0.431546)
			(stroke
				(width 0.254)
				(type default)
			)
			(fill no)
			(layer "F.SilkS")
		)
		(fp_poly
			(pts
				(xy 0.21463 -0.450088) (xy 1.56337 -0.450088) (xy 1.56337 1.75006) (xy 0.21463 1.75006)
			)
			(stroke
				(width 0)
				(type default)
			)
			(fill no)
			(layer "F.CrtYd")
		)
		(fp_line
			(start 1.56337 1.75006)
			(end 0.21463 1.75006)
			(stroke
				(width 0.1)
				(type default)
			)
			(layer "F.Fab")
		)
		(fp_line
			(start 1.56337 -0.450088)
			(end 1.56337 1.75006)
			(stroke
				(width 0.1)
				(type default)
			)
			(layer "F.Fab")
		)
		(fp_line
			(start 0.21463 1.75006)
			(end 0.21463 -0.450088)
			(stroke
				(width 0.1)
				(type default)
			)
			(layer "F.Fab")
		)
		(fp_line
			(start 0.21463 -0.450088)
			(end 1.56337 -0.450088)
			(stroke
				(width 0.1)
				(type default)
			)
			(layer "F.Fab")
		)
		(fp_circle
			(center -0.4699 -0.8382)
			(end -0.5969 -0.8382)
			(stroke
				(width 0.254)
				(type default)
			)
			(fill no)
			(layer "F.Fab")
		)
		(pad "1" smd rect
			(at 0 0 180)
			(size 1.016 0.381)
			(layers "F.Cu" "F.Mask" "F.Paste")
			(net "Net_6467")
		)
		(pad "2" smd rect
			(at 0 0.649986 180)
			(size 1.016 0.381)
			(layers "F.Cu" "F.Mask" "F.Paste")
			(net "RST_BMC_DDR3_BUF_IN_N")
		)
		(pad "3" smd rect
			(at 0 1.299972 180)
			(size 1.016 0.381)
			(layers "F.Cu" "F.Mask" "F.Paste")
			(net "GND")
		)
		(pad "4" smd rect
			(at 1.778 1.299972 180)
			(size 1.016 0.381)
			(layers "F.Cu" "F.Mask" "F.Paste")
			(net "RST_BMC_DDR3_R_N")
		)
		(pad "5" smd rect
			(at 1.778 0 180)
			(size 1.016 0.381)
			(layers "F.Cu" "F.Mask" "F.Paste")
			(net "P3V3_STBY")
		)
	)
	(footprint ""
		(layer "F.Cu")
		(at 394.1064 -0.2286)
		(property "Reference" "R8G12"
			(at 0 0 0)
			(layer "F.SilkS")
			(hide yes)
			(effects
				(font
					(size 1.27 1.27)
				)
			)
		)
		(property "Value" ""
			(at 0 0 0)
			(layer "F.Fab")
			(effects
				(font
					(size 1.27 1.27)
				)
			)
		)
		(duplicate_pad_numbers_are_jumpers no)
		(fp_poly
			(pts
				(xy -0.2794 -0.1016) (xy 0.2794 -0.1016) (xy 0.2794 0.9906) (xy -0.2794 0.9906)
			)
			(stroke
				(width 0)
				(type default)
			)
			(fill no)
			(layer "F.CrtYd")
		)
		(fp_line
			(start -0.2794 -0.1016)
			(end -0.2794 0.9906)
			(stroke
				(width 0.1)
				(type default)
			)
			(layer "F.Fab")
		)
		(fp_line
			(start -0.2794 0.9906)
			(end 0.2794 0.9906)
			(stroke
				(width 0.1)
				(type default)
			)
			(layer "F.Fab")
		)
		(fp_line
			(start 0.2794 -0.1016)
			(end -0.2794 -0.1016)
			(stroke
				(width 0.1)
				(type default)
			)
			(layer "F.Fab")
		)
		(fp_line
			(start 0.2794 0.9906)
			(end 0.2794 -0.1016)
			(stroke
				(width 0.1)
				(type default)
			)
			(layer "F.Fab")
		)
		(pad "1" smd rect
			(at 0 0)
			(size 0.508 0.508)
			(layers "F.Cu" "F.Mask" "F.Paste")
			(net "JTAG_PCH_GBE_TMS")
		)
		(pad "2" smd rect
			(at 0 0.889)
			(size 0.508 0.508)
			(layers "F.Cu" "F.Mask" "F.Paste")
			(net "JTAG_TMS")
		)
		(zone
			(layer "F.Cu")
			(hatch none 0.5)
			(connect_pads
				(clearance 0)
			)
			(min_thickness 0.25)
			(keepout
				(tracks allowed)
				(vias not_allowed)
				(pads allowed)
				(copperpour not_allowed)
				(footprints allowed)
			)
			(placement
				(enabled no)
				(sheetname "")
			)
			(fill
				(thermal_gap 0.5)
				(thermal_bridge_width 0.5)
				(island_removal_mode 0)
			)
			(polygon
				(pts
					(xy 393.8524 0.0254) (xy 394.3604 0.0254) (xy 394.3604 0.4064) (xy 393.8524 0.4064)
				)
			)
		)
		(zone
			(layer "F.Cu")
			(hatch none 0.5)
			(connect_pads
				(clearance 0)
			)
			(min_thickness 0.25)
			(keepout
				(tracks not_allowed)
				(vias allowed)
				(pads allowed)
				(copperpour not_allowed)
				(footprints allowed)
			)
			(placement
				(enabled no)
				(sheetname "")
			)
			(fill
				(thermal_gap 0.5)
				(thermal_bridge_width 0.5)
				(island_removal_mode 0)
			)
			(polygon
				(pts
					(xy 393.8524 0.4064) (xy 394.3604 0.4064) (xy 394.3604 0.0254) (xy 393.8524 0.0254)
				)
			)
		)
	)
	(footprint ""
		(layer "F.Cu")
		(at 93.20784 -73.318116)
		(property "Reference" "C2D30"
			(at 0 0 0)
			(layer "F.SilkS")
			(hide yes)
			(effects
				(font
					(size 1.27 1.27)
				)
			)
		)
		(property "Value" ""
			(at 0 0 0)
			(layer "F.Fab")
			(effects
				(font
					(size 1.27 1.27)
				)
			)
		)
		(duplicate_pad_numbers_are_jumpers no)
		(fp_poly
			(pts
				(xy -0.4953 -0.2032) (xy 0.4953 -0.2032) (xy 0.4953 1.6002) (xy -0.4953 1.6002)
			)
			(stroke
				(width 0)
				(type default)
			)
			(fill no)
			(layer "F.CrtYd")
		)
		(fp_line
			(start -0.4953 -0.2032)
			(end 0.4953 -0.2032)
			(stroke
				(width 0.1)
				(type default)
			)
			(layer "F.Fab")
		)
		(fp_line
			(start -0.4953 1.6002)
			(end -0.4953 -0.2032)
			(stroke
				(width 0.1)
				(type default)
			)
			(layer "F.Fab")
		)
		(fp_line
			(start 0.4953 -0.2032)
			(end 0.4953 1.6002)
			(stroke
				(width 0.1)
				(type default)
			)
			(layer "F.Fab")
		)
		(fp_line
			(start 0.4953 1.6002)
			(end -0.4953 1.6002)
			(stroke
				(width 0.1)
				(type default)
			)
			(layer "F.Fab")
		)
		(pad "1" smd rect
			(at 0 0)
			(size 0.762 0.889)
			(layers "F.Cu" "F.Mask" "F.Paste")
			(net "PVCCIN_CPU1")
		)
		(pad "2" smd rect
			(at 0 1.397)
			(size 0.762 0.889)
			(layers "F.Cu" "F.Mask" "F.Paste")
			(net "GND")
		)
		(zone
			(layer "F.Cu")
			(hatch none 0.5)
			(connect_pads
				(clearance 0)
			)
			(min_thickness 0.25)
			(keepout
				(tracks not_allowed)
				(vias allowed)
				(pads allowed)
				(copperpour not_allowed)
				(footprints allowed)
			)
			(placement
				(enabled no)
				(sheetname "")
			)
			(fill
				(thermal_gap 0.5)
				(thermal_bridge_width 0.5)
				(island_removal_mode 0)
			)
			(polygon
				(pts
					(xy 92.82684 -72.873616) (xy 93.58884 -72.873616) (xy 93.58884 -72.365616) (xy 92.82684 -72.365616)
				)
			)
		)
	)
	(footprint ""
		(layer "F.Cu")
		(at 18.525744 -51.3842 180)
		(property "Reference" "Q1E1"
			(at 0 0 180)
			(layer "F.SilkS")
			(hide yes)
			(effects
				(font
					(size 1.27 1.27)
				)
			)
		)
		(property "Value" "*"
			(at -4.8514 -0.40005 180)
			(unlocked yes)
			(layer "F.Fab")
			(hide yes)
			(effects
				(font
					(size 0.889 0.889)
					(thickness 0.1524)
				)
			)
		)
		(property "Device Type" "2SB2907A-B0-00001-GP_DISCRET-GA"
			(at -4.8514 -1.92405 180)
			(unlocked yes)
			(layer "F.Fab")
			(hide yes)
			(effects
				(font
					(size 0.889 0.889)
					(thickness 0.1524)
				)
			)
		)
		(duplicate_pad_numbers_are_jumpers no)
		(fp_line
			(start 3.3274 0.8255)
			(end 2.59334 0.8255)
			(stroke
				(width 0.1524)
				(type default)
			)
			(layer "F.SilkS")
		)
		(fp_line
			(start 3.3274 -0.8255)
			(end 3.3274 0.8255)
			(stroke
				(width 0.1524)
				(type default)
			)
			(layer "F.SilkS")
		)
		(fp_line
			(start 2.460752 -0.8255)
			(end 3.3274 -0.8255)
			(stroke
				(width 0.1524)
				(type default)
			)
			(layer "F.SilkS")
		)
		(fp_line
			(start -2.188718 -1.3208)
			(end 2.188718 -1.3208)
			(stroke
				(width 0.1524)
				(type default)
			)
			(layer "F.SilkS")
		)
		(fp_line
			(start -2.59334 0.8255)
			(end -3.3274 0.8255)
			(stroke
				(width 0.1524)
				(type default)
			)
			(layer "F.SilkS")
		)
		(fp_line
			(start -3.3274 0.8255)
			(end -3.3274 -0.8255)
			(stroke
				(width 0.1524)
				(type default)
			)
			(layer "F.SilkS")
		)
		(fp_line
			(start -3.3274 -0.8255)
			(end -2.460752 -0.8255)
			(stroke
				(width 0.1524)
				(type default)
			)
			(layer "F.SilkS")
		)
		(fp_arc
			(start 2.59334 0.8255)
			(mid 0 2.870159)
			(end -2.59334 0.8255)
			(stroke
				(width 0.1524)
				(type default)
			)
			(layer "F.SilkS")
		)
		(fp_arc
			(start 2.188718 -1.3208)
			(mid 2.337892 -1.080376)
			(end 2.460752 -0.8255)
			(stroke
				(width 0.1524)
				(type default)
			)
			(layer "F.SilkS")
		)
		(fp_arc
			(start -2.460752 -0.8255)
			(mid -2.337885 -1.080372)
			(end -2.188718 -1.3208)
			(stroke
				(width 0.1524)
				(type default)
			)
			(layer "F.SilkS")
		)
		(fp_poly
			(pts
				(arc
					(start 2.413 0.2286)
					(mid 0 2.616334)
					(end -2.413 0.2286)
				)
				(xy -2.7432 0.2286) (xy -2.7432 -0.2286)
				(arc
					(start -2.374138 -0.2286)
					(mid -2.252325 -0.662833)
					(end -2.051812 -1.0668)
				)
				(arc
					(start 2.051812 -1.0668)
					(mid 2.252296 -0.662822)
					(end 2.374138 -0.2286)
				)
				(xy 2.7432 -0.2286) (xy 2.7432 0.2286)
			)
			(stroke
				(width 0)
				(type default)
			)
			(fill no)
			(layer "F.CrtYd")
		)
		(fp_poly
			(pts
				(arc
					(start 2.786634 1.0795)
					(mid 0 3.124369)
					(end -2.786634 1.0795)
				)
				(xy -3.5814 1.0795) (xy -3.5814 -1.0795)
				(arc
					(start -2.624328 -1.0795)
					(mid -2.483414 -1.33481)
					(end -2.31775 -1.5748)
				)
				(xy -0.000762 -1.5748) (xy -0.000762 -1.067054)
				(arc
					(start -2.052066 -1.067054)
					(mid -2.252571 -0.663082)
					(end -2.374392 -0.228854)
				)
				(xy -2.743454 -0.228854) (xy -2.743454 0.228854)
				(arc
					(start -2.413254 0.228854)
					(mid 0 2.61659)
					(end 2.413254 0.228854)
				)
				(xy 2.743454 0.228854) (xy 2.743454 -0.228854)
				(arc
					(start 2.374392 -0.228854)
					(mid 2.252549 -0.663073)
					(end 2.052066 -1.067054)
				)
				(xy 0.000762 -1.067054) (xy 0.000762 -1.5748)
				(arc
					(start 2.31775 -1.5748)
					(mid 2.483417 -1.334811)
					(end 2.624328 -1.0795)
				)
				(xy 3.5814 -1.0795) (xy 3.5814 1.0795)
			)
			(stroke
				(width 0)
				(type default)
			)
			(fill no)
			(layer "F.CrtYd")
		)
		(fp_poly
			(pts
				(arc
					(start 2.786634 1.0795)
					(mid 0 3.124369)
					(end -2.786634 1.0795)
				)
				(xy -3.5814 1.0795) (xy -3.5814 -1.0795)
				(arc
					(start -2.624328 -1.0795)
					(mid -2.483414 -1.33481)
					(end -2.31775 -1.5748)
				)
				(arc
					(start 2.31775 -1.5748)
					(mid 2.483417 -1.334811)
					(end 2.624328 -1.0795)
				)
				(xy 3.5814 -1.0795) (xy 3.5814 1.0795)
			)
			(stroke
				(width 0)
				(type default)
			)
			(fill no)
			(layer "F.Fab")
		)
		(pad "B" thru_hole circle
			(at 0 0 180)
			(size 1.143 1.143)
			(drill 0.7874)
			(layers "*.Cu" "*.Mask")
			(remove_unused_layers no)
			(net "ISENSE_TMP421_2_BC")
			(clearance 0.1778)
			(thermal_gap 0.1778)
		)
		(pad "C" thru_hole circle
			(at -2.500122 0 180)
			(size 1.143 1.143)
			(drill 0.7874)
			(layers "*.Cu" "*.Mask")
			(remove_unused_layers no)
			(net "ISENSE_TMP421_2_BC")
			(clearance 0.1778)
			(thermal_gap 0.1778)
		)
		(pad "E" thru_hole circle
			(at 2.500122 0 180)
			(size 1.143 1.143)
			(drill 0.7874)
			(layers "*.Cu" "*.Mask")
			(remove_unused_layers no)
			(net "ISENSE_TMP421_2_E")
			(clearance 0.1778)
			(thermal_gap 0.1778)
		)
	)
	(footprint ""
		(layer "F.Cu")
		(at 186.4868 -76.4921)
		(property "Reference" "R4D31"
			(at 0 0 0)
			(layer "F.SilkS")
			(hide yes)
			(effects
				(font
					(size 1.27 1.27)
				)
			)
		)
		(property "Value" ""
			(at 0 0 0)
			(layer "F.Fab")
			(effects
				(font
					(size 1.27 1.27)
				)
			)
		)
		(duplicate_pad_numbers_are_jumpers no)
		(fp_rect
			(start -0.2794 0.9906)
			(end 0.2794 -0.1016)
			(stroke
				(width 0)
				(type default)
			)
			(fill no)
			(layer "F.CrtYd")
		)
		(fp_line
			(start -0.2794 -0.1016)
			(end -0.2794 0.9906)
			(stroke
				(width 0.1)
				(type default)
			)
			(layer "F.Fab")
		)
		(fp_line
			(start -0.2794 0.9906)
			(end 0.2794 0.9906)
			(stroke
				(width 0.1)
				(type default)
			)
			(layer "F.Fab")
		)
		(fp_line
			(start 0.2794 -0.1016)
			(end -0.2794 -0.1016)
			(stroke
				(width 0.1)
				(type default)
			)
			(layer "F.Fab")
		)
		(fp_line
			(start 0.2794 0.9906)
			(end 0.2794 -0.1016)
			(stroke
				(width 0.1)
				(type default)
			)
			(layer "F.Fab")
		)
		(pad "1" smd rect
			(at 0 0)
			(size 0.508 0.508)
			(layers "F.Cu" "F.Mask" "F.Paste")
			(net "P3V3_STBY")
		)
		(pad "2" smd rect
			(at 0 0.889)
			(size 0.508 0.508)
			(layers "F.Cu" "F.Mask" "F.Paste")
			(net "PU_VR_PVCCIN_CPU0_IMON")
		)
		(zone
			(layer "F.Cu")
			(hatch none 0.5)
			(connect_pads
				(clearance 0)
			)
			(min_thickness 0.25)
			(keepout
				(tracks not_allowed)
				(vias allowed)
				(pads allowed)
				(copperpour not_allowed)
				(footprints allowed)
			)
			(placement
				(enabled no)
				(sheetname "")
			)
			(fill
				(thermal_gap 0.5)
				(thermal_bridge_width 0.5)
				(island_removal_mode 0)
			)
			(polygon
				(pts
					(xy 186.2328 -75.8571) (xy 186.7408 -75.8571) (xy 186.7408 -76.2381) (xy 186.2328 -76.2381)
				)
			)
		)
		(zone
			(layer "F.Cu")
			(hatch none 0.5)
			(connect_pads
				(clearance 0)
			)
			(min_thickness 0.25)
			(keepout
				(tracks allowed)
				(vias not_allowed)
				(pads allowed)
				(copperpour not_allowed)
				(footprints allowed)
			)
			(placement
				(enabled no)
				(sheetname "")
			)
			(fill
				(thermal_gap 0.5)
				(thermal_bridge_width 0.5)
				(island_removal_mode 0)
			)
			(polygon
				(pts
					(xy 186.2328 -75.8571) (xy 186.7408 -75.8571) (xy 186.7408 -76.2381) (xy 186.2328 -76.2381)
				)
			)
		)
	)
)
